# S9S_MB_2U (Grand Teton) — schematic netlist excerpt (pin names and nets, part order shuffled) for the footprints in the layout excerpt that follows; sources: Cadence DE-HDL packaged netlist, KiCad conversion of 03242023_DA0F0TMBIJ0_F0T_Motherboard_J_brd_V01_OCP.brd

C1508  Q_CAP  18PF 50V 5% C0G  pkg 0402  page 179 : A = XTAL_PCH_RTC1 ; B = GND
C918  Q_CAP_DIFFBUS  DIFF BUS_0.22UF 6.3V 20% X6S  pkg C0201  page 173 : \1\ = P5E_CPU0_PE0_TX_C_DN<7> ; \2\ = P5E_CPU0_PE0_TX_DN<7>
C104  Q_CAP  27PF 50V 5% EMPTY  pkg 0402  page 179 : A = XTAL_PCH_25M_OUT ; B = GND

(kicad_pcb
	(version 20260206)
	(generator "pcbnew")
	(generator_version "10.0")
	(general
		(thickness 1.6)
		(legacy_teardrops no)
	)
	(paper "A4")
	(title_block
		(title "03242023_DA0F0TMBIJ0_F0T_Motherboard_J_brd_V01_OCP.brd")
		(comment 1 "Grand Teton / footprints 621-623 of 6105")
	)
	(layers
		(0 "F.Cu" signal "TOP")
		(4 "In1.Cu" signal "GND")
		(6 "In2.Cu" signal "IN1")
		(8 "In3.Cu" signal "GND1")
		(10 "In4.Cu" signal "IN2")
		(12 "In5.Cu" signal "GND2")
		(14 "In6.Cu" signal "IN3")
		(16 "In7.Cu" signal "GND3")
		(18 "In8.Cu" signal "VCC")
		(20 "In9.Cu" signal "VCC1")
		(22 "In10.Cu" signal "GND4")
		(24 "In11.Cu" signal "IN4")
		(26 "In12.Cu" signal "GND5")
		(28 "In13.Cu" signal "IN5")
		(30 "In14.Cu" signal "GND6")
		(32 "In15.Cu" signal "IN6")
		(34 "In16.Cu" signal "GND7")
		(2 "B.Cu" signal "BOTTOM")
		(9 "F.Adhes" user "F.Adhesive")
		(11 "B.Adhes" user "B.Adhesive")
		(13 "F.Paste" user "Package Geometry/Pastemask Top")
		(15 "B.Paste" user "Package Geometry/Pastemask Bottom")
		(5 "F.SilkS" user "Ref Des/Silkscreen Top")
		(7 "B.SilkS" user "Ref Des/Silkscreen Bottom")
		(1 "F.Mask" user "Board Geometry/Soldermask Top")
		(3 "B.Mask" user "Board Geometry/Soldermask Bottom")
		(17 "Dwgs.User" user "User.Drawings")
		(19 "Cmts.User" user "User.Comments")
		(21 "Eco1.User" user "User.Eco1")
		(23 "Eco2.User" user "User.Eco2")
		(25 "Edge.Cuts" user "Board Geometry/Outline")
		(27 "Margin" user)
		(31 "F.CrtYd" user "Package Geometry/Place Bound Top")
		(29 "B.CrtYd" user "Package Geometry/Place Bound Bottom")
		(35 "F.Fab" user "Ref Des/Assembly Top")
		(33 "B.Fab" user "Ref Des/Assembly Bottom")
	)
	(footprint ""
		(layer "F.Cu")
		(at 336.947256 -66.424556)
		(property "Reference" "C104"
			(at 0 0 0)
			(layer "F.SilkS")
			(hide yes)
			(effects
				(font
					(size 1.27 1.27)
				)
			)
		)
		(property "Value" ""
			(at 0 0 0)
			(layer "F.Fab")
			(effects
				(font
					(size 1.27 1.27)
				)
			)
		)
		(duplicate_pad_numbers_are_jumpers no)
		(fp_line
			(start -0.7874 -0.4064)
			(end 0.7874 -0.4064)
			(stroke
				(width 0.1524)
				(type default)
			)
			(layer "F.SilkS")
		)
		(fp_line
			(start -0.7874 0.4064)
			(end -0.7874 -0.4064)
			(stroke
				(width 0.1524)
				(type default)
			)
			(layer "F.SilkS")
		)
		(fp_line
			(start 0.7874 -0.4064)
			(end 0.7874 0.4064)
			(stroke
				(width 0.1524)
				(type default)
			)
			(layer "F.SilkS")
		)
		(fp_line
			(start 0.7874 0.4064)
			(end -0.7874 0.4064)
			(stroke
				(width 0.1524)
				(type default)
			)
			(layer "F.SilkS")
		)
		(fp_line
			(start -0.67945 -0.305054)
			(end -0.12065 -0.305054)
			(stroke
				(width 0.1)
				(type default)
			)
			(layer "F.Fab")
		)
		(fp_line
			(start -0.67945 0.3048)
			(end -0.67945 -0.305054)
			(stroke
				(width 0.1)
				(type default)
			)
			(layer "F.Fab")
		)
		(fp_line
			(start -0.12065 -0.305054)
			(end -0.12065 -0.2794)
			(stroke
				(width 0.1)
				(type default)
			)
			(layer "F.Fab")
		)
		(fp_line
			(start -0.12065 -0.2794)
			(end 0.12065 -0.2794)
			(stroke
				(width 0.1)
				(type default)
			)
			(layer "F.Fab")
		)
		(fp_line
			(start -0.12065 0.2794)
			(end -0.12065 0.3048)
			(stroke
				(width 0.1)
				(type default)
			)
			(layer "F.Fab")
		)
		(fp_line
			(start -0.12065 0.3048)
			(end -0.67945 0.3048)
			(stroke
				(width 0.1)
				(type default)
			)
			(layer "F.Fab")
		)
		(fp_line
			(start 0.120396 0.2794)
			(end -0.12065 0.2794)
			(stroke
				(width 0.1)
				(type default)
			)
			(layer "F.Fab")
		)
		(fp_line
			(start 0.120396 0.3048)
			(end 0.120396 0.2794)
			(stroke
				(width 0.1)
				(type default)
			)
			(layer "F.Fab")
		)
		(fp_line
			(start 0.12065 -0.3048)
			(end 0.67945 -0.3048)
			(stroke
				(width 0.1)
				(type default)
			)
			(layer "F.Fab")
		)
		(fp_line
			(start 0.12065 -0.2794)
			(end 0.12065 -0.3048)
			(stroke
				(width 0.1)
				(type default)
			)
			(layer "F.Fab")
		)
		(fp_line
			(start 0.67945 -0.3048)
			(end 0.67945 0.3048)
			(stroke
				(width 0.1)
				(type default)
			)
			(layer "F.Fab")
		)
		(fp_line
			(start 0.67945 0.3048)
			(end 0.120396 0.3048)
			(stroke
				(width 0.1)
				(type default)
			)
			(layer "F.Fab")
		)
		(pad "1" smd circle
			(at -0.40005 0)
			(size 0 0)
			(layers "F.Cu" "F.Mask" "F.Paste")
			(net "XTAL_PCH_25M_OUT")
		)
		(pad "2" smd circle
			(at 0.40005 0)
			(size 0 0)
			(layers "F.Cu" "F.Mask" "F.Paste")
			(net "GND")
		)
	)
	(footprint ""
		(layer "F.Cu")
		(at 324.9168 -34.178748 135)
		(property "Reference" "C1508"
			(at 0 0 135)
			(layer "F.SilkS")
			(hide yes)
			(effects
				(font
					(size 1.27 1.27)
				)
			)
		)
		(property "Value" ""
			(at 0 0 135)
			(layer "F.Fab")
			(effects
				(font
					(size 1.27 1.27)
				)
			)
		)
		(duplicate_pad_numbers_are_jumpers no)
		(fp_line
			(start 0.787389 -0.406267)
			(end 0.787389 0.406267)
			(stroke
				(width 0.1524)
				(type default)
			)
			(layer "F.SilkS")
		)
		(fp_line
			(start 0.787389 0.406267)
			(end -0.787389 0.406267)
			(stroke
				(width 0.1524)
				(type default)
			)
			(layer "F.SilkS")
		)
		(fp_line
			(start -0.787389 -0.406267)
			(end 0.787389 -0.406267)
			(stroke
				(width 0.1524)
				(type default)
			)
			(layer "F.SilkS")
		)
		(fp_line
			(start -0.787389 0.406267)
			(end -0.787389 -0.406267)
			(stroke
				(width 0.1524)
				(type default)
			)
			(layer "F.SilkS")
		)
		(fp_line
			(start 0.679446 -0.30479)
			(end 0.679446 0.30479)
			(stroke
				(width 0.1)
				(type default)
			)
			(layer "F.Fab")
		)
		(fp_line
			(start 0.120515 -0.30479)
			(end 0.679446 -0.30479)
			(stroke
				(width 0.1)
				(type default)
			)
			(layer "F.Fab")
		)
		(fp_line
			(start 0.120695 -0.279466)
			(end 0.120515 -0.30479)
			(stroke
				(width 0.1)
				(type default)
			)
			(layer "F.Fab")
		)
		(fp_line
			(start 0.679446 0.30479)
			(end 0.120515 0.30479)
			(stroke
				(width 0.1)
				(type default)
			)
			(layer "F.Fab")
		)
		(fp_line
			(start -0.120695 -0.304969)
			(end -0.120695 -0.279466)
			(stroke
				(width 0.1)
				(type default)
			)
			(layer "F.Fab")
		)
		(fp_line
			(start -0.120695 -0.279466)
			(end 0.120695 -0.279466)
			(stroke
				(width 0.1)
				(type default)
			)
			(layer "F.Fab")
		)
		(fp_line
			(start 0.120335 0.279466)
			(end -0.120695 0.279466)
			(stroke
				(width 0.1)
				(type default)
			)
			(layer "F.Fab")
		)
		(fp_line
			(start 0.120515 0.30479)
			(end 0.120335 0.279466)
			(stroke
				(width 0.1)
				(type default)
			)
			(layer "F.Fab")
		)
		(fp_line
			(start -0.679446 -0.305149)
			(end -0.120695 -0.304969)
			(stroke
				(width 0.1)
				(type default)
			)
			(layer "F.Fab")
		)
		(fp_line
			(start -0.120695 0.279466)
			(end -0.120515 0.30479)
			(stroke
				(width 0.1)
				(type default)
			)
			(layer "F.Fab")
		)
		(fp_line
			(start -0.120515 0.30479)
			(end -0.679446 0.30479)
			(stroke
				(width 0.1)
				(type default)
			)
			(layer "F.Fab")
		)
		(fp_line
			(start -0.679446 0.30479)
			(end -0.679446 -0.305149)
			(stroke
				(width 0.1)
				(type default)
			)
			(layer "F.Fab")
		)
		(pad "1" smd circle
			(at -0.40005 0 135)
			(size 0 0)
			(layers "F.Cu" "F.Mask" "F.Paste")
			(net "XTAL_PCH_RTC1")
		)
		(pad "2" smd circle
			(at 0.40005 0 135)
			(size 0 0)
			(layers "F.Cu" "F.Mask" "F.Paste")
			(net "GND")
		)
	)
	(footprint ""
		(layer "F.Cu")
		(at 329.806808 -408.517344 -90)
		(property "Reference" "C918"
			(at 0 0 270)
			(layer "F.SilkS")
			(hide yes)
			(effects
				(font
					(size 1.27 1.27)
				)
			)
		)
		(property "Value" ""
			(at 0 0 270)
			(layer "F.Fab")
			(effects
				(font
					(size 1.27 1.27)
				)
			)
		)
		(duplicate_pad_numbers_are_jumpers no)
		(fp_line
			(start -0.299974 0.150114)
			(end -0.299974 -0.150114)
			(stroke
				(width 0.1)
				(type default)
			)
			(layer "F.Fab")
		)
		(fp_line
			(start 0.299974 0.150114)
			(end -0.299974 0.150114)
			(stroke
				(width 0.1)
				(type default)
			)
			(layer "F.Fab")
		)
		(fp_line
			(start -0.299974 -0.150114)
			(end 0.299974 -0.150114)
			(stroke
				(width 0.1)
				(type default)
			)
			(layer "F.Fab")
		)
		(fp_line
			(start 0.299974 -0.150114)
			(end 0.299974 0.150114)
			(stroke
				(width 0.1)
				(type default)
			)
			(layer "F.Fab")
		)
		(pad "1" smd rect
			(at -0.2667 0 270)
			(size 0.3048 0.381)
			(layers "F.Cu" "F.Mask" "F.Paste")
			(net "P5E_CPU0_PE0_TX_C_DN<7>")
		)
		(pad "2" smd rect
			(at 0.2667 0 270)
			(size 0.3048 0.381)
			(layers "F.Cu" "F.Mask" "F.Paste")
			(net "P5E_CPU0_PE0_TX_DN<7>")
		)
	)
)
